(kicad_pcb
	(version 20260206)
	(generator "pcbnew")
	(generator_version "10.0")
	(general
		(thickness 1.6)
		(legacy_teardrops no)
	)
	(paper "A4")
	(title_block
		(title "01162023_DA0F0TEBIF0_F0T_Expander_BD_F_brd_V02_OCP.brd")
		(comment 1 "Grand Teton / footprint 6619 of 9728 (PEX0), pads 1073-1187 of 2397")
	)
	(layers
		(0 "F.Cu" signal "TOP")
		(4 "In1.Cu" signal "GND")
		(6 "In2.Cu" signal "VCC")
		(8 "In3.Cu" signal "VCC1")
		(10 "In4.Cu" signal "GND1")
		(12 "In5.Cu" signal "IN1")
		(14 "In6.Cu" signal "GND2")
		(16 "In7.Cu" signal "IN2")
		(18 "In8.Cu" signal "GND3")
		(20 "In9.Cu" signal "IN3")
		(22 "In10.Cu" signal "GND4")
		(24 "In11.Cu" signal "IN4")
		(26 "In12.Cu" signal "GND5")
		(28 "In13.Cu" signal "IN5")
		(30 "In14.Cu" signal "GND6")
		(32 "In15.Cu" signal "IN6")
		(34 "In16.Cu" signal "GND7")
		(2 "B.Cu" signal "BOTTOM")
		(9 "F.Adhes" user "F.Adhesive")
		(11 "B.Adhes" user "B.Adhesive")
		(13 "F.Paste" user "Package Geometry/Pastemask Top")
		(15 "B.Paste" user "Package Geometry/Pastemask Bottom")
		(5 "F.SilkS" user "Ref Des/Silkscreen Top")
		(7 "B.SilkS" user "Ref Des/Silkscreen Bottom")
		(1 "F.Mask" user "Board Geometry/Soldermask Top")
		(3 "B.Mask" user "Board Geometry/Soldermask Bottom")
		(17 "Dwgs.User" user "User.Drawings")
		(19 "Cmts.User" user "User.Comments")
		(21 "Eco1.User" user "User.Eco1")
		(23 "Eco2.User" user "User.Eco2")
		(25 "Edge.Cuts" user "Board Geometry/Outline")
		(27 "Margin" user)
		(31 "F.CrtYd" user "Package Geometry/Place Bound Top")
		(29 "B.CrtYd" user "Package Geometry/Place Bound Bottom")
		(35 "F.Fab" user "Ref Des/Assembly Top")
		(33 "B.Fab" user "Ref Des/Assembly Bottom")
	)
	(footprint ""
		(layer "F.Cu")
		(at 59.649868 -295.89984)
		(property "Reference" "PEX0"
			(at -3.360166 35.566858 0)
			(unlocked yes)
			(layer "F.SilkS")
			(effects
				(font
					(size 2.032 1.524)
					(thickness 0.1524)
				)
				(justify left)
			)
		)
		(property "Value" ""
			(at 0 0 0)
			(layer "F.Fab")
			(effects
				(font
					(size 1.27 1.27)
				)
			)
		)
		(duplicate_pad_numbers_are_jumpers no)
		(pad "B46" smd circle
			(at 19.949922 -21.850096)
			(size 0.4572 0.4572)
			(layers "F.Cu" "F.Mask" "F.Paste")
			(net "GND")
		)
		(pad "B47" smd circle
			(at 20.899882 -21.850096)
			(size 0.4572 0.4572)
			(layers "F.Cu" "F.Mask" "F.Paste")
			(net "P5E_PEX0_STN4_RX_DP<72>")
		)
		(pad "B48" smd circle
			(at 21.850096 -21.850096)
			(size 0.4572 0.4572)
			(layers "F.Cu" "F.Mask" "F.Paste")
			(net "GND")
		)
		(pad "B49" smd circle
			(at 22.800056 -21.850096)
			(size 0.4572 0.4572)
			(layers "F.Cu" "F.Mask" "F.Paste")
			(net "GND")
		)
		(pad "BA1" smd circle
			(at -22.800056 15.200122)
			(size 0.4572 0.4572)
			(layers "F.Cu" "F.Mask" "F.Paste")
			(net "GND")
		)
		(pad "BA2" smd circle
			(at -21.850096 15.200122)
			(size 0.4572 0.4572)
			(layers "F.Cu" "F.Mask" "F.Paste")
			(net "GND")
		)
		(pad "BA3" smd circle
			(at -20.899882 15.200122)
			(size 0.4572 0.4572)
			(layers "F.Cu" "F.Mask" "F.Paste")
			(net "GND")
		)
		(pad "BA4" smd circle
			(at -19.949922 15.200122)
			(size 0.4572 0.4572)
			(layers "F.Cu" "F.Mask" "F.Paste")
			(net "Net_2761")
		)
		(pad "BA5" smd circle
			(at -18.999962 15.200122)
			(size 0.4572 0.4572)
			(layers "F.Cu" "F.Mask" "F.Paste")
			(net "GND")
		)
		(pad "BA6" smd circle
			(at -18.050002 15.200122)
			(size 0.4572 0.4572)
			(layers "F.Cu" "F.Mask" "F.Paste")
			(net "Net_2763")
		)
		(pad "BA7" smd circle
			(at -17.100042 15.200122)
			(size 0.4572 0.4572)
			(layers "F.Cu" "F.Mask" "F.Paste")
			(net "GND")
		)
		(pad "BA8" smd circle
			(at -16.150082 15.200122)
			(size 0.4572 0.4572)
			(layers "F.Cu" "F.Mask" "F.Paste")
			(net "Net_2765")
		)
		(pad "BA9" smd circle
			(at -15.200122 15.200122)
			(size 0.4572 0.4572)
			(layers "F.Cu" "F.Mask" "F.Paste")
			(net "GND")
		)
		(pad "BA10" smd circle
			(at -14.249908 15.200122)
			(size 0.4572 0.4572)
			(layers "F.Cu" "F.Mask" "F.Paste")
			(net "P5E_PEX0_STN2_TX_DP<46>")
		)
		(pad "BA11" smd circle
			(at -13.299948 15.200122)
			(size 0.4572 0.4572)
			(layers "F.Cu" "F.Mask" "F.Paste")
			(net "GND")
		)
		(pad "BA12" smd circle
			(at -12.349988 15.200122)
			(size 0.4572 0.4572)
			(layers "F.Cu" "F.Mask" "F.Paste")
			(net "P5E_PEX0_STN2_TX_DP<44>")
		)
		(pad "BA13" smd circle
			(at -11.400028 15.200122)
			(size 0.4572 0.4572)
			(layers "F.Cu" "F.Mask" "F.Paste")
			(net "GND")
		)
		(pad "BA14" smd circle
			(at -10.450068 15.200122)
			(size 0.4572 0.4572)
			(layers "F.Cu" "F.Mask" "F.Paste")
			(net "P5E_PEX0_STN2_TX_DP<42>")
		)
		(pad "BA15" smd circle
			(at -9.500108 15.200122)
			(size 0.4572 0.4572)
			(layers "F.Cu" "F.Mask" "F.Paste")
			(net "GND")
		)
		(pad "BA16" smd circle
			(at -8.549894 15.200122)
			(size 0.4572 0.4572)
			(layers "F.Cu" "F.Mask" "F.Paste")
			(net "P5E_PEX0_STN2_TX_DP<40>")
		)
		(pad "BA17" smd circle
			(at -7.599934 15.200122)
			(size 0.4572 0.4572)
			(layers "F.Cu" "F.Mask" "F.Paste")
			(net "GND")
		)
		(pad "BA18" smd circle
			(at -6.649974 15.200122)
			(size 0.4572 0.4572)
			(layers "F.Cu" "F.Mask" "F.Paste")
			(net "P5E_PEX0_STN2_TX_DP<38>")
		)
		(pad "BA19" smd circle
			(at -5.700014 15.200122)
			(size 0.4572 0.4572)
			(layers "F.Cu" "F.Mask" "F.Paste")
			(net "GND")
		)
		(pad "BA20" smd circle
			(at -4.750054 15.200122)
			(size 0.4572 0.4572)
			(layers "F.Cu" "F.Mask" "F.Paste")
			(net "P5E_PEX0_STN2_TX_DP<36>")
		)
		(pad "BA21" smd circle
			(at -3.800094 15.200122)
			(size 0.4572 0.4572)
			(layers "F.Cu" "F.Mask" "F.Paste")
			(net "GND")
		)
		(pad "BA22" smd circle
			(at -2.84988 15.200122)
			(size 0.4572 0.4572)
			(layers "F.Cu" "F.Mask" "F.Paste")
			(net "P5E_PEX0_STN2_TX_DP<34>")
		)
		(pad "BA23" smd circle
			(at -1.89992 15.200122)
			(size 0.4572 0.4572)
			(layers "F.Cu" "F.Mask" "F.Paste")
			(net "GND")
		)
		(pad "BA24" smd circle
			(at -0.94996 15.200122)
			(size 0.4572 0.4572)
			(layers "F.Cu" "F.Mask" "F.Paste")
			(net "P5E_PEX0_STN2_TX_DP<32>")
		)
		(pad "BA25" smd circle
			(at 0 15.200122)
			(size 0.4572 0.4572)
			(layers "F.Cu" "F.Mask" "F.Paste")
			(net "GND")
		)
		(pad "BA26" smd circle
			(at 0.94996 15.200122)
			(size 0.4572 0.4572)
			(layers "F.Cu" "F.Mask" "F.Paste")
			(net "P5E_PEX0_STN1_TX_DN<17>")
		)
		(pad "BA27" smd circle
			(at 1.89992 15.200122)
			(size 0.4572 0.4572)
			(layers "F.Cu" "F.Mask" "F.Paste")
			(net "GND")
		)
		(pad "BA28" smd circle
			(at 2.84988 15.200122)
			(size 0.4572 0.4572)
			(layers "F.Cu" "F.Mask" "F.Paste")
			(net "P5E_PEX0_STN1_TX_DN<19>")
		)
		(pad "BA29" smd circle
			(at 3.800094 15.200122)
			(size 0.4572 0.4572)
			(layers "F.Cu" "F.Mask" "F.Paste")
			(net "GND")
		)
		(pad "BA30" smd circle
			(at 4.750054 15.200122)
			(size 0.4572 0.4572)
			(layers "F.Cu" "F.Mask" "F.Paste")
			(net "P5E_PEX0_STN1_TX_DN<21>")
		)
		(pad "BA31" smd circle
			(at 5.700014 15.200122)
			(size 0.4572 0.4572)
			(layers "F.Cu" "F.Mask" "F.Paste")
			(net "GND")
		)
		(pad "BA32" smd circle
			(at 6.649974 15.200122)
			(size 0.4572 0.4572)
			(layers "F.Cu" "F.Mask" "F.Paste")
			(net "P5E_PEX0_STN1_TX_DN<23>")
		)
		(pad "BA33" smd circle
			(at 7.599934 15.200122)
			(size 0.4572 0.4572)
			(layers "F.Cu" "F.Mask" "F.Paste")
			(net "GND")
		)
		(pad "BA34" smd circle
			(at 8.549894 15.200122)
			(size 0.4572 0.4572)
			(layers "F.Cu" "F.Mask" "F.Paste")
			(net "P5E_PEX0_STN1_TX_DN<25>")
		)
		(pad "BA35" smd circle
			(at 9.500108 15.200122)
			(size 0.4572 0.4572)
			(layers "F.Cu" "F.Mask" "F.Paste")
			(net "GND")
		)
		(pad "BA36" smd circle
			(at 10.450068 15.200122)
			(size 0.4572 0.4572)
			(layers "F.Cu" "F.Mask" "F.Paste")
			(net "P5E_PEX0_STN1_TX_DN<27>")
		)
		(pad "BA37" smd circle
			(at 11.400028 15.200122)
			(size 0.4572 0.4572)
			(layers "F.Cu" "F.Mask" "F.Paste")
			(net "GND")
		)
		(pad "BA38" smd circle
			(at 12.349988 15.200122)
			(size 0.4572 0.4572)
			(layers "F.Cu" "F.Mask" "F.Paste")
			(net "P5E_PEX0_STN1_TX_DN<29>")
		)
		(pad "BA39" smd circle
			(at 13.299948 15.200122)
			(size 0.4572 0.4572)
			(layers "F.Cu" "F.Mask" "F.Paste")
			(net "GND")
		)
		(pad "BA40" smd circle
			(at 14.249908 15.200122)
			(size 0.4572 0.4572)
			(layers "F.Cu" "F.Mask" "F.Paste")
			(net "P5E_PEX0_STN1_TX_DN<31>")
		)
		(pad "BA41" smd circle
			(at 15.200122 15.200122)
			(size 0.4572 0.4572)
			(layers "F.Cu" "F.Mask" "F.Paste")
			(net "GND")
		)
		(pad "BA42" smd circle
			(at 16.150082 15.200122)
			(size 0.4572 0.4572)
			(layers "F.Cu" "F.Mask" "F.Paste")
			(net "P5E_PEX0_STN0_TX_DN<14>")
		)
		(pad "BA43" smd circle
			(at 17.100042 15.200122)
			(size 0.4572 0.4572)
			(layers "F.Cu" "F.Mask" "F.Paste")
			(net "GND")
		)
		(pad "BA44" smd circle
			(at 18.050002 15.200122)
			(size 0.4572 0.4572)
			(layers "F.Cu" "F.Mask" "F.Paste")
			(net "P5E_PEX0_STN0_TX_DN<12>")
		)
		(pad "BA45" smd circle
			(at 18.999962 15.200122)
			(size 0.4572 0.4572)
			(layers "F.Cu" "F.Mask" "F.Paste")
			(net "GND")
		)
		(pad "BA46" smd circle
			(at 19.949922 15.200122)
			(size 0.4572 0.4572)
			(layers "F.Cu" "F.Mask" "F.Paste")
			(net "P5E_PEX0_STN0_TX_DP<10>")
		)
		(pad "BA47" smd circle
			(at 20.899882 15.200122)
			(size 0.4572 0.4572)
			(layers "F.Cu" "F.Mask" "F.Paste")
			(net "GND")
		)
		(pad "BA48" smd circle
			(at 21.850096 15.200122)
			(size 0.4572 0.4572)
			(layers "F.Cu" "F.Mask" "F.Paste")
			(net "GND")
		)
		(pad "BA49" smd circle
			(at 22.800056 15.200122)
			(size 0.4572 0.4572)
			(layers "F.Cu" "F.Mask" "F.Paste")
			(net "GND")
		)
		(pad "BB1" smd circle
			(at -22.800056 16.150082)
			(size 0.4572 0.4572)
			(layers "F.Cu" "F.Mask" "F.Paste")
			(net "Net_2744")
		)
		(pad "BB2" smd circle
			(at -21.850096 16.150082)
			(size 0.4572 0.4572)
			(layers "F.Cu" "F.Mask" "F.Paste")
			(net "Net_2758")
		)
		(pad "BB3" smd circle
			(at -20.899882 16.150082)
			(size 0.4572 0.4572)
			(layers "F.Cu" "F.Mask" "F.Paste")
			(net "GND")
		)
		(pad "BB4" smd circle
			(at -19.949922 16.150082)
			(size 0.4572 0.4572)
			(layers "F.Cu" "F.Mask" "F.Paste")
			(net "Net_2747")
		)
		(pad "BB5" smd circle
			(at -18.999962 16.150082)
			(size 0.4572 0.4572)
			(layers "F.Cu" "F.Mask" "F.Paste")
			(net "GND")
		)
		(pad "BB6" smd circle
			(at -18.050002 16.150082)
			(size 0.4572 0.4572)
			(layers "F.Cu" "F.Mask" "F.Paste")
			(net "Net_2749")
		)
		(pad "BB7" smd circle
			(at -17.100042 16.150082)
			(size 0.4572 0.4572)
			(layers "F.Cu" "F.Mask" "F.Paste")
			(net "GND")
		)
		(pad "BB8" smd circle
			(at -16.150082 16.150082)
			(size 0.4572 0.4572)
			(layers "F.Cu" "F.Mask" "F.Paste")
			(net "Net_2751")
		)
		(pad "BB9" smd circle
			(at -15.200122 16.150082)
			(size 0.4572 0.4572)
			(layers "F.Cu" "F.Mask" "F.Paste")
			(net "GND")
		)
		(pad "BB10" smd circle
			(at -14.249908 16.150082)
			(size 0.4572 0.4572)
			(layers "F.Cu" "F.Mask" "F.Paste")
			(net "P5E_PEX0_STN2_TX_DN<46>")
		)
		(pad "BB11" smd circle
			(at -13.299948 16.150082)
			(size 0.4572 0.4572)
			(layers "F.Cu" "F.Mask" "F.Paste")
			(net "GND")
		)
		(pad "BB12" smd circle
			(at -12.349988 16.150082)
			(size 0.4572 0.4572)
			(layers "F.Cu" "F.Mask" "F.Paste")
			(net "P5E_PEX0_STN2_TX_DN<44>")
		)
		(pad "BB13" smd circle
			(at -11.400028 16.150082)
			(size 0.4572 0.4572)
			(layers "F.Cu" "F.Mask" "F.Paste")
			(net "GND")
		)
		(pad "BB14" smd circle
			(at -10.450068 16.150082)
			(size 0.4572 0.4572)
			(layers "F.Cu" "F.Mask" "F.Paste")
			(net "P5E_PEX0_STN2_TX_DN<42>")
		)
		(pad "BB15" smd circle
			(at -9.500108 16.150082)
			(size 0.4572 0.4572)
			(layers "F.Cu" "F.Mask" "F.Paste")
			(net "GND")
		)
		(pad "BB16" smd circle
			(at -8.549894 16.150082)
			(size 0.4572 0.4572)
			(layers "F.Cu" "F.Mask" "F.Paste")
			(net "P5E_PEX0_STN2_TX_DN<40>")
		)
		(pad "BB17" smd circle
			(at -7.599934 16.150082)
			(size 0.4572 0.4572)
			(layers "F.Cu" "F.Mask" "F.Paste")
			(net "GND")
		)
		(pad "BB18" smd circle
			(at -6.649974 16.150082)
			(size 0.4572 0.4572)
			(layers "F.Cu" "F.Mask" "F.Paste")
			(net "P5E_PEX0_STN2_TX_DN<38>")
		)
		(pad "BB19" smd circle
			(at -5.700014 16.150082)
			(size 0.4572 0.4572)
			(layers "F.Cu" "F.Mask" "F.Paste")
			(net "GND")
		)
		(pad "BB20" smd circle
			(at -4.750054 16.150082)
			(size 0.4572 0.4572)
			(layers "F.Cu" "F.Mask" "F.Paste")
			(net "P5E_PEX0_STN2_TX_DN<36>")
		)
		(pad "BB21" smd circle
			(at -3.800094 16.150082)
			(size 0.4572 0.4572)
			(layers "F.Cu" "F.Mask" "F.Paste")
			(net "GND")
		)
		(pad "BB22" smd circle
			(at -2.84988 16.150082)
			(size 0.4572 0.4572)
			(layers "F.Cu" "F.Mask" "F.Paste")
			(net "P5E_PEX0_STN2_TX_DN<34>")
		)
		(pad "BB23" smd circle
			(at -1.89992 16.150082)
			(size 0.4572 0.4572)
			(layers "F.Cu" "F.Mask" "F.Paste")
			(net "GND")
		)
		(pad "BB24" smd circle
			(at -0.94996 16.150082)
			(size 0.4572 0.4572)
			(layers "F.Cu" "F.Mask" "F.Paste")
			(net "P5E_PEX0_STN2_TX_DN<32>")
		)
		(pad "BB25" smd circle
			(at 0 16.150082)
			(size 0.4572 0.4572)
			(layers "F.Cu" "F.Mask" "F.Paste")
			(net "GND")
		)
		(pad "BB26" smd circle
			(at 0.94996 16.150082)
			(size 0.4572 0.4572)
			(layers "F.Cu" "F.Mask" "F.Paste")
			(net "P5E_PEX0_STN1_TX_DP<17>")
		)
		(pad "BB27" smd circle
			(at 1.89992 16.150082)
			(size 0.4572 0.4572)
			(layers "F.Cu" "F.Mask" "F.Paste")
			(net "GND")
		)
		(pad "BB28" smd circle
			(at 2.84988 16.150082)
			(size 0.4572 0.4572)
			(layers "F.Cu" "F.Mask" "F.Paste")
			(net "P5E_PEX0_STN1_TX_DP<19>")
		)
		(pad "BB29" smd circle
			(at 3.800094 16.150082)
			(size 0.4572 0.4572)
			(layers "F.Cu" "F.Mask" "F.Paste")
			(net "GND")
		)
		(pad "BB30" smd circle
			(at 4.750054 16.150082)
			(size 0.4572 0.4572)
			(layers "F.Cu" "F.Mask" "F.Paste")
			(net "P5E_PEX0_STN1_TX_DP<21>")
		)
		(pad "BB31" smd circle
			(at 5.700014 16.150082)
			(size 0.4572 0.4572)
			(layers "F.Cu" "F.Mask" "F.Paste")
			(net "GND")
		)
		(pad "BB32" smd circle
			(at 6.649974 16.150082)
			(size 0.4572 0.4572)
			(layers "F.Cu" "F.Mask" "F.Paste")
			(net "P5E_PEX0_STN1_TX_DP<23>")
		)
		(pad "BB33" smd circle
			(at 7.599934 16.150082)
			(size 0.4572 0.4572)
			(layers "F.Cu" "F.Mask" "F.Paste")
			(net "GND")
		)
		(pad "BB34" smd circle
			(at 8.549894 16.150082)
			(size 0.4572 0.4572)
			(layers "F.Cu" "F.Mask" "F.Paste")
			(net "P5E_PEX0_STN1_TX_DP<25>")
		)
		(pad "BB35" smd circle
			(at 9.500108 16.150082)
			(size 0.4572 0.4572)
			(layers "F.Cu" "F.Mask" "F.Paste")
			(net "GND")
		)
		(pad "BB36" smd circle
			(at 10.450068 16.150082)
			(size 0.4572 0.4572)
			(layers "F.Cu" "F.Mask" "F.Paste")
			(net "P5E_PEX0_STN1_TX_DP<27>")
		)
		(pad "BB37" smd circle
			(at 11.400028 16.150082)
			(size 0.4572 0.4572)
			(layers "F.Cu" "F.Mask" "F.Paste")
			(net "GND")
		)
		(pad "BB38" smd circle
			(at 12.349988 16.150082)
			(size 0.4572 0.4572)
			(layers "F.Cu" "F.Mask" "F.Paste")
			(net "P5E_PEX0_STN1_TX_DP<29>")
		)
		(pad "BB39" smd circle
			(at 13.299948 16.150082)
			(size 0.4572 0.4572)
			(layers "F.Cu" "F.Mask" "F.Paste")
			(net "GND")
		)
		(pad "BB40" smd circle
			(at 14.249908 16.150082)
			(size 0.4572 0.4572)
			(layers "F.Cu" "F.Mask" "F.Paste")
			(net "P5E_PEX0_STN1_TX_DP<31>")
		)
		(pad "BB41" smd circle
			(at 15.200122 16.150082)
			(size 0.4572 0.4572)
			(layers "F.Cu" "F.Mask" "F.Paste")
			(net "GND")
		)
		(pad "BB42" smd circle
			(at 16.150082 16.150082)
			(size 0.4572 0.4572)
			(layers "F.Cu" "F.Mask" "F.Paste")
			(net "P5E_PEX0_STN0_TX_DP<14>")
		)
		(pad "BB43" smd circle
			(at 17.100042 16.150082)
			(size 0.4572 0.4572)
			(layers "F.Cu" "F.Mask" "F.Paste")
			(net "GND")
		)
		(pad "BB44" smd circle
			(at 18.050002 16.150082)
			(size 0.4572 0.4572)
			(layers "F.Cu" "F.Mask" "F.Paste")
			(net "P5E_PEX0_STN0_TX_DP<12>")
		)
		(pad "BB45" smd circle
			(at 18.999962 16.150082)
			(size 0.4572 0.4572)
			(layers "F.Cu" "F.Mask" "F.Paste")
			(net "GND")
		)
		(pad "BB46" smd circle
			(at 19.949922 16.150082)
			(size 0.4572 0.4572)
			(layers "F.Cu" "F.Mask" "F.Paste")
			(net "P5E_PEX0_STN0_TX_DN<10>")
		)
		(pad "BB47" smd circle
			(at 20.899882 16.150082)
			(size 0.4572 0.4572)
			(layers "F.Cu" "F.Mask" "F.Paste")
			(net "GND")
		)
		(pad "BB48" smd circle
			(at 21.850096 16.150082)
			(size 0.4572 0.4572)
			(layers "F.Cu" "F.Mask" "F.Paste")
			(net "P5E_PEX0_STN0_TX_DP<7>")
		)
		(pad "BB49" smd circle
			(at 22.800056 16.150082)
			(size 0.4572 0.4572)
			(layers "F.Cu" "F.Mask" "F.Paste")
			(net "P5E_PEX0_STN0_TX_DN<7>")
		)
		(pad "BC1" smd circle
			(at -22.800056 17.100042)
			(size 0.4572 0.4572)
			(layers "F.Cu" "F.Mask" "F.Paste")
			(net "GND")
		)
		(pad "BC2" smd circle
			(at -21.850096 17.100042)
			(size 0.4572 0.4572)
			(layers "F.Cu" "F.Mask" "F.Paste")
			(net "GND")
		)
		(pad "BC3" smd circle
			(at -20.899882 17.100042)
			(size 0.4572 0.4572)
			(layers "F.Cu" "F.Mask" "F.Paste")
			(net "Net_2760")
		)
		(pad "BC4" smd circle
			(at -19.949922 17.100042)
			(size 0.4572 0.4572)
			(layers "F.Cu" "F.Mask" "F.Paste")
			(net "GND")
		)
		(pad "BC5" smd circle
			(at -18.999962 17.100042)
			(size 0.4572 0.4572)
			(layers "F.Cu" "F.Mask" "F.Paste")
			(net "Net_2762")
		)
		(pad "BC6" smd circle
			(at -18.050002 17.100042)
			(size 0.4572 0.4572)
			(layers "F.Cu" "F.Mask" "F.Paste")
			(net "GND")
		)
		(pad "BC7" smd circle
			(at -17.100042 17.100042)
			(size 0.4572 0.4572)
			(layers "F.Cu" "F.Mask" "F.Paste")
			(net "Net_2764")
		)
		(pad "BC8" smd circle
			(at -16.150082 17.100042)
			(size 0.4572 0.4572)
			(layers "F.Cu" "F.Mask" "F.Paste")
			(net "GND")
		)
		(pad "BC9" smd circle
			(at -15.200122 17.100042)
			(size 0.4572 0.4572)
			(layers "F.Cu" "F.Mask" "F.Paste")
			(net "P5E_PEX0_STN2_TX_DP<47>")
		)
		(pad "BC10" smd circle
			(at -14.249908 17.100042)
			(size 0.4572 0.4572)
			(layers "F.Cu" "F.Mask" "F.Paste")
			(net "GND")
		)
		(pad "BC11" smd circle
			(at -13.299948 17.100042)
			(size 0.4572 0.4572)
			(layers "F.Cu" "F.Mask" "F.Paste")
			(net "P5E_PEX0_STN2_TX_DP<45>")
		)
		(pad "BC12" smd circle
			(at -12.349988 17.100042)
			(size 0.4572 0.4572)
			(layers "F.Cu" "F.Mask" "F.Paste")
			(net "GND")
		)
		(pad "BC13" smd circle
			(at -11.400028 17.100042)
			(size 0.4572 0.4572)
			(layers "F.Cu" "F.Mask" "F.Paste")
			(net "P5E_PEX0_STN2_TX_DP<43>")
		)
	)
)
